(kicad_pcb
	(version 20260206)
	(generator "pcbnew")
	(generator_version "10.0")
	(general
		(thickness 1.6)
		(legacy_teardrops no)
	)
	(paper "A4")
	(title_block
		(title "Bryce Canyon_SCC_16316-1_OCP.brd")
		(comment 1 "Bryce Canyon / footprints 984-991 of 1561")
	)
	(layers
		(0 "F.Cu" signal "TOP")
		(4 "In1.Cu" signal "L2GND")
		(6 "In2.Cu" signal "L3")
		(8 "In3.Cu" signal "L4VCC")
		(10 "In4.Cu" signal "L5VCC")
		(12 "In5.Cu" signal "L6")
		(14 "In6.Cu" signal "L7GND")
		(2 "B.Cu" signal "BOTTOM")
		(9 "F.Adhes" user "F.Adhesive")
		(11 "B.Adhes" user "B.Adhesive")
		(13 "F.Paste" user "Package Geometry/Pastemask Top")
		(15 "B.Paste" user "Package Geometry/Pastemask Bottom")
		(5 "F.SilkS" user "Ref Des/Silkscreen Top")
		(7 "B.SilkS" user "Ref Des/Silkscreen Bottom")
		(1 "F.Mask" user "Board Geometry/Soldermask Top")
		(3 "B.Mask" user "Board Geometry/Soldermask Bottom")
		(17 "Dwgs.User" user "User.Drawings")
		(19 "Cmts.User" user "User.Comments")
		(21 "Eco1.User" user "User.Eco1")
		(23 "Eco2.User" user "User.Eco2")
		(25 "Edge.Cuts" user "Board Geometry/Outline")
		(27 "Margin" user)
		(31 "F.CrtYd" user "Package Geometry/Place Bound Top")
		(29 "B.CrtYd" user "Package Geometry/Place Bound Bottom")
		(35 "F.Fab" user "Ref Des/Assembly Top")
		(33 "B.Fab" user "Ref Des/Assembly Bottom")
	)
	(footprint ""
		(layer "B.Cu")
		(at 192.73901 -34.641282 -90)
		(property "Reference" "R190"
			(at 0 0 90)
			(layer "B.SilkS")
			(hide yes)
			(effects
				(font
					(size 1.27 1.27)
				)
				(justify mirror)
			)
		)
		(property "Value" "2K2R2F-GP"
			(at -0.064008 -3.993896 270)
			(unlocked yes)
			(layer "B.Fab")
			(hide yes)
			(effects
				(font
					(size 1.016 1.016)
					(thickness 0.1524)
				)
				(justify mirror)
			)
		)
		(property "Device Type" "R402H16"
			(at -0.064008 -5.517896 270)
			(unlocked yes)
			(layer "B.Fab")
			(hide yes)
			(effects
				(font
					(size 1.016 1.016)
					(thickness 0.1524)
				)
				(justify mirror)
			)
		)
		(duplicate_pad_numbers_are_jumpers no)
		(fp_line
			(start -0.508 -0.9398)
			(end 0.508 -0.9398)
			(stroke
				(width 0.1524)
				(type default)
			)
			(layer "B.SilkS")
		)
		(fp_line
			(start 0.508 -0.9398)
			(end 0.508 0.9398)
			(stroke
				(width 0.1524)
				(type default)
			)
			(layer "B.SilkS")
		)
		(fp_rect
			(start 0.508 0.9398)
			(end -0.508 -0.9398)
			(stroke
				(width 0)
				(type default)
			)
			(fill no)
			(layer "B.CrtYd")
		)
		(fp_rect
			(start 0.508 0.9398)
			(end -0.508 -0.9398)
			(stroke
				(width 0)
				(type default)
			)
			(fill no)
			(layer "B.Fab")
		)
		(pad "1" smd custom
			(at 0 -0.4445 90)
			(size 0.1397 0.1397)
			(layers "B.Cu" "B.Mask" "B.Paste")
			(net "P1V8_C")
			(options
				(clearance outline)
				(anchor circle)
			)
			(primitives
				(gr_poly
					(pts
						(arc
							(start -0.1778 0.2794)
							(mid -0.249642 0.249642)
							(end -0.2794 0.1778)
						)
						(arc
							(start -0.2794 -0.1778)
							(mid -0.249642 -0.249642)
							(end -0.1778 -0.2794)
						)
						(arc
							(start 0.1778 -0.2794)
							(mid 0.249642 -0.249642)
							(end 0.2794 -0.1778)
						)
						(arc
							(start 0.2794 0.1778)
							(mid 0.249642 0.249642)
							(end 0.1778 0.2794)
						)
					)
					(width 0)
					(fill yes)
				)
			)
		)
		(pad "2" smd custom
			(at 0 0.4445 90)
			(size 0.1397 0.1397)
			(layers "B.Cu" "B.Mask" "B.Paste")
			(net "I2C_IOC_4_SCL")
			(options
				(clearance outline)
				(anchor circle)
			)
			(primitives
				(gr_poly
					(pts
						(arc
							(start -0.1778 0.2794)
							(mid -0.249642 0.249642)
							(end -0.2794 0.1778)
						)
						(arc
							(start -0.2794 -0.1778)
							(mid -0.249642 -0.249642)
							(end -0.1778 -0.2794)
						)
						(arc
							(start 0.1778 -0.2794)
							(mid 0.249642 -0.249642)
							(end 0.2794 -0.1778)
						)
						(arc
							(start 0.2794 0.1778)
							(mid 0.249642 0.249642)
							(end 0.1778 0.2794)
						)
					)
					(width 0)
					(fill yes)
				)
			)
		)
	)
	(footprint ""
		(layer "B.Cu")
		(at 203.884784 -35.3314 180)
		(property "Reference" "R209"
			(at 0 0 0)
			(layer "B.SilkS")
			(hide yes)
			(effects
				(font
					(size 1.27 1.27)
				)
				(justify mirror)
			)
		)
		(property "Value" "4K7R2F-GP"
			(at -0.064008 -3.993896 180)
			(unlocked yes)
			(layer "B.Fab")
			(hide yes)
			(effects
				(font
					(size 1.016 1.016)
					(thickness 0.1524)
				)
				(justify mirror)
			)
		)
		(property "Device Type" "R402H16"
			(at -0.064008 -5.517896 180)
			(unlocked yes)
			(layer "B.Fab")
			(hide yes)
			(effects
				(font
					(size 1.016 1.016)
					(thickness 0.1524)
				)
				(justify mirror)
			)
		)
		(duplicate_pad_numbers_are_jumpers no)
		(fp_line
			(start 0.508 -0.9398)
			(end 0.508 0.9398)
			(stroke
				(width 0.1524)
				(type default)
			)
			(layer "B.SilkS")
		)
		(fp_line
			(start -0.508 -0.9398)
			(end 0.508 -0.9398)
			(stroke
				(width 0.1524)
				(type default)
			)
			(layer "B.SilkS")
		)
		(fp_rect
			(start 0.508 0.9398)
			(end -0.508 -0.9398)
			(stroke
				(width 0)
				(type default)
			)
			(fill no)
			(layer "B.CrtYd")
		)
		(fp_rect
			(start 0.508 0.9398)
			(end -0.508 -0.9398)
			(stroke
				(width 0)
				(type default)
			)
			(fill no)
			(layer "B.Fab")
		)
		(pad "1" smd custom
			(at 0 -0.4445)
			(size 0.1397 0.1397)
			(layers "B.Cu" "B.Mask" "B.Paste")
			(net "P1V8_C")
			(options
				(clearance outline)
				(anchor circle)
			)
			(primitives
				(gr_poly
					(pts
						(arc
							(start -0.1778 0.2794)
							(mid -0.249642 0.249642)
							(end -0.2794 0.1778)
						)
						(arc
							(start -0.2794 -0.1778)
							(mid -0.249642 -0.249642)
							(end -0.1778 -0.2794)
						)
						(arc
							(start 0.1778 -0.2794)
							(mid 0.249642 -0.249642)
							(end 0.2794 -0.1778)
						)
						(arc
							(start 0.2794 0.1778)
							(mid 0.249642 0.249642)
							(end 0.1778 0.2794)
						)
					)
					(width 0)
					(fill yes)
				)
			)
		)
		(pad "2" smd custom
			(at 0 0.4445)
			(size 0.1397 0.1397)
			(layers "B.Cu" "B.Mask" "B.Paste")
			(net "IOC_EEPROM_A0")
			(options
				(clearance outline)
				(anchor circle)
			)
			(primitives
				(gr_poly
					(pts
						(arc
							(start -0.1778 0.2794)
							(mid -0.249642 0.249642)
							(end -0.2794 0.1778)
						)
						(arc
							(start -0.2794 -0.1778)
							(mid -0.249642 -0.249642)
							(end -0.1778 -0.2794)
						)
						(arc
							(start 0.1778 -0.2794)
							(mid 0.249642 -0.249642)
							(end 0.2794 -0.1778)
						)
						(arc
							(start 0.2794 0.1778)
							(mid 0.249642 0.249642)
							(end 0.1778 0.2794)
						)
					)
					(width 0)
					(fill yes)
				)
			)
		)
	)
	(footprint ""
		(layer "B.Cu")
		(at 125.001528 -75.837542 180)
		(property "Reference" "C118"
			(at 0 0 0)
			(layer "B.SilkS")
			(hide yes)
			(effects
				(font
					(size 1.27 1.27)
				)
				(justify mirror)
			)
		)
		(property "Value" "SC10U6D3V2MX-GP-U"
			(at 1.524 -1.905 180)
			(unlocked yes)
			(layer "B.Fab")
			(hide yes)
			(effects
				(font
					(size 1.016 1.016)
					(thickness 0.1524)
				)
				(justify mirror)
			)
		)
		(property "Device Type" "C402-TO0D2H28"
			(at 1.524 -3.429 180)
			(unlocked yes)
			(layer "B.Fab")
			(hide yes)
			(effects
				(font
					(size 1.016 1.016)
					(thickness 0.1524)
				)
				(justify mirror)
			)
		)
		(duplicate_pad_numbers_are_jumpers no)
		(fp_rect
			(start 0.4826 0.889)
			(end -0.4826 -0.889)
			(stroke
				(width 0)
				(type default)
			)
			(fill no)
			(layer "B.CrtYd")
		)
		(fp_rect
			(start 0.4826 0.889)
			(end -0.4826 -0.889)
			(stroke
				(width 0)
				(type default)
			)
			(fill no)
			(layer "B.Fab")
		)
		(pad "1" smd custom
			(at 0 -0.4572)
			(size 0.1524 0.1524)
			(layers "B.Cu" "B.Mask" "B.Paste")
			(net "P1V8_E")
			(options
				(clearance outline)
				(anchor circle)
			)
			(primitives
				(gr_poly
					(pts
						(arc
							(start -0.254 -0.3048)
							(mid -0.325842 -0.275042)
							(end -0.3556 -0.2032)
						)
						(arc
							(start -0.3556 0.2032)
							(mid -0.325842 0.275042)
							(end -0.254 0.3048)
						)
						(arc
							(start 0.254 0.3048)
							(mid 0.325842 0.275042)
							(end 0.3556 0.2032)
						)
						(arc
							(start 0.3556 -0.2032)
							(mid 0.325842 -0.275042)
							(end 0.254 -0.3048)
						)
					)
					(width 0)
					(fill yes)
				)
			)
		)
		(pad "2" smd custom
			(at 0 0.4572)
			(size 0.1524 0.1524)
			(layers "B.Cu" "B.Mask" "B.Paste")
			(net "GND")
			(options
				(clearance outline)
				(anchor circle)
			)
			(primitives
				(gr_poly
					(pts
						(arc
							(start -0.254 -0.3048)
							(mid -0.325842 -0.275042)
							(end -0.3556 -0.2032)
						)
						(arc
							(start -0.3556 0.2032)
							(mid -0.325842 0.275042)
							(end -0.254 0.3048)
						)
						(arc
							(start 0.254 0.3048)
							(mid 0.325842 0.275042)
							(end 0.3556 0.2032)
						)
						(arc
							(start 0.3556 -0.2032)
							(mid 0.325842 -0.275042)
							(end 0.254 -0.3048)
						)
					)
					(width 0)
					(fill yes)
				)
			)
		)
	)
	(footprint ""
		(layer "B.Cu")
		(at 202.21194 -46.8884 180)
		(property "Reference" "R193"
			(at 0 0 0)
			(layer "B.SilkS")
			(hide yes)
			(effects
				(font
					(size 1.27 1.27)
				)
				(justify mirror)
			)
		)
		(property "Value" "0R2J-2-GP"
			(at -0.064008 -3.993896 180)
			(unlocked yes)
			(layer "B.Fab")
			(hide yes)
			(effects
				(font
					(size 1.016 1.016)
					(thickness 0.1524)
				)
				(justify mirror)
			)
		)
		(property "Device Type" "R402H16"
			(at -0.064008 -5.517896 180)
			(unlocked yes)
			(layer "B.Fab")
			(hide yes)
			(effects
				(font
					(size 1.016 1.016)
					(thickness 0.1524)
				)
				(justify mirror)
			)
		)
		(duplicate_pad_numbers_are_jumpers no)
		(fp_line
			(start 0.508 -0.9398)
			(end 0.508 0.9398)
			(stroke
				(width 0.1524)
				(type default)
			)
			(layer "B.SilkS")
		)
		(fp_line
			(start -0.508 -0.9398)
			(end 0.508 -0.9398)
			(stroke
				(width 0.1524)
				(type default)
			)
			(layer "B.SilkS")
		)
		(fp_rect
			(start 0.508 0.9398)
			(end -0.508 -0.9398)
			(stroke
				(width 0)
				(type default)
			)
			(fill no)
			(layer "B.CrtYd")
		)
		(fp_rect
			(start 0.508 0.9398)
			(end -0.508 -0.9398)
			(stroke
				(width 0)
				(type default)
			)
			(fill no)
			(layer "B.Fab")
		)
		(pad "1" smd custom
			(at 0 -0.4445)
			(size 0.1397 0.1397)
			(layers "B.Cu" "B.Mask" "B.Paste")
			(net "IOC_EEPROM_WP")
			(options
				(clearance outline)
				(anchor circle)
			)
			(primitives
				(gr_poly
					(pts
						(arc
							(start -0.1778 0.2794)
							(mid -0.249642 0.249642)
							(end -0.2794 0.1778)
						)
						(arc
							(start -0.2794 -0.1778)
							(mid -0.249642 -0.249642)
							(end -0.1778 -0.2794)
						)
						(arc
							(start 0.1778 -0.2794)
							(mid 0.249642 -0.249642)
							(end 0.2794 -0.1778)
						)
						(arc
							(start 0.2794 0.1778)
							(mid 0.249642 0.249642)
							(end 0.1778 0.2794)
						)
					)
					(width 0)
					(fill yes)
				)
			)
		)
		(pad "2" smd custom
			(at 0 0.4445)
			(size 0.1397 0.1397)
			(layers "B.Cu" "B.Mask" "B.Paste")
			(net "GND")
			(options
				(clearance outline)
				(anchor circle)
			)
			(primitives
				(gr_poly
					(pts
						(arc
							(start -0.1778 0.2794)
							(mid -0.249642 0.249642)
							(end -0.2794 0.1778)
						)
						(arc
							(start -0.2794 -0.1778)
							(mid -0.249642 -0.249642)
							(end -0.1778 -0.2794)
						)
						(arc
							(start 0.1778 -0.2794)
							(mid 0.249642 -0.249642)
							(end 0.2794 -0.1778)
						)
						(arc
							(start 0.2794 0.1778)
							(mid 0.249642 0.249642)
							(end 0.1778 0.2794)
						)
					)
					(width 0)
					(fill yes)
				)
			)
		)
	)
	(footprint ""
		(layer "B.Cu")
		(at 175.739298 -67.608958 180)
		(property "Reference" "R288"
			(at 0 0 0)
			(layer "B.SilkS")
			(hide yes)
			(effects
				(font
					(size 1.27 1.27)
				)
				(justify mirror)
			)
		)
		(property "Value" "0R2J-2-GP"
			(at -0.064008 -3.993896 180)
			(unlocked yes)
			(layer "B.Fab")
			(hide yes)
			(effects
				(font
					(size 1.016 1.016)
					(thickness 0.1524)
				)
				(justify mirror)
			)
		)
		(property "Device Type" "R402H16"
			(at -0.064008 -5.517896 180)
			(unlocked yes)
			(layer "B.Fab")
			(hide yes)
			(effects
				(font
					(size 1.016 1.016)
					(thickness 0.1524)
				)
				(justify mirror)
			)
		)
		(duplicate_pad_numbers_are_jumpers no)
		(fp_line
			(start 0.508 -0.9398)
			(end 0.508 0.9398)
			(stroke
				(width 0.1524)
				(type default)
			)
			(layer "B.SilkS")
		)
		(fp_line
			(start -0.508 -0.9398)
			(end 0.508 -0.9398)
			(stroke
				(width 0.1524)
				(type default)
			)
			(layer "B.SilkS")
		)
		(fp_rect
			(start 0.508 0.9398)
			(end -0.508 -0.9398)
			(stroke
				(width 0)
				(type default)
			)
			(fill no)
			(layer "B.CrtYd")
		)
		(fp_rect
			(start 0.508 0.9398)
			(end -0.508 -0.9398)
			(stroke
				(width 0)
				(type default)
			)
			(fill no)
			(layer "B.Fab")
		)
		(pad "1" smd custom
			(at 0 -0.4445)
			(size 0.1397 0.1397)
			(layers "B.Cu" "B.Mask" "B.Paste")
			(net "IOC_VREF_SET_LS")
			(options
				(clearance outline)
				(anchor circle)
			)
			(primitives
				(gr_poly
					(pts
						(arc
							(start -0.1778 0.2794)
							(mid -0.249642 0.249642)
							(end -0.2794 0.1778)
						)
						(arc
							(start -0.2794 -0.1778)
							(mid -0.249642 -0.249642)
							(end -0.1778 -0.2794)
						)
						(arc
							(start 0.1778 -0.2794)
							(mid 0.249642 -0.249642)
							(end 0.2794 -0.1778)
						)
						(arc
							(start 0.2794 0.1778)
							(mid 0.249642 0.249642)
							(end 0.1778 0.2794)
						)
					)
					(width 0)
					(fill yes)
				)
			)
		)
		(pad "2" smd custom
			(at 0 0.4445)
			(size 0.1397 0.1397)
			(layers "B.Cu" "B.Mask" "B.Paste")
			(net "SYS_RST_Q8")
			(options
				(clearance outline)
				(anchor circle)
			)
			(primitives
				(gr_poly
					(pts
						(arc
							(start -0.1778 0.2794)
							(mid -0.249642 0.249642)
							(end -0.2794 0.1778)
						)
						(arc
							(start -0.2794 -0.1778)
							(mid -0.249642 -0.249642)
							(end -0.1778 -0.2794)
						)
						(arc
							(start 0.1778 -0.2794)
							(mid 0.249642 -0.249642)
							(end 0.2794 -0.1778)
						)
						(arc
							(start 0.2794 0.1778)
							(mid 0.249642 0.249642)
							(end 0.1778 0.2794)
						)
					)
					(width 0)
					(fill yes)
				)
			)
		)
	)
	(footprint ""
		(layer "B.Cu")
		(at 112.649 -64.4779)
		(property "Reference" "C170"
			(at 0 0 0)
			(layer "B.SilkS")
			(hide yes)
			(effects
				(font
					(size 1.27 1.27)
				)
				(justify mirror)
			)
		)
		(property "Value" "SCD1U6D3V1KX-GP"
			(at 2.8321 -1.7399 0)
			(unlocked yes)
			(layer "B.Fab")
			(hide yes)
			(effects
				(font
					(size 1.016 1.016)
					(thickness 0.1524)
				)
				(justify mirror)
			)
		)
		(property "Device Type" "C0201H13"
			(at 2.8321 -3.2639 0)
			(unlocked yes)
			(layer "B.Fab")
			(hide yes)
			(effects
				(font
					(size 1.016 1.016)
					(thickness 0.1524)
				)
				(justify mirror)
			)
		)
		(duplicate_pad_numbers_are_jumpers no)
		(fp_rect
			(start 0.2794 0.6477)
			(end -0.2794 -0.6477)
			(stroke
				(width 0)
				(type default)
			)
			(fill no)
			(layer "B.CrtYd")
		)
		(fp_rect
			(start 0.2794 0.6477)
			(end -0.2794 -0.6477)
			(stroke
				(width 0)
				(type default)
			)
			(fill no)
			(layer "B.Fab")
		)
		(pad "1" smd custom
			(at 0 -0.2794 180)
			(size 0.0762 0.0762)
			(layers "B.Cu" "B.Mask" "B.Paste")
			(net "P0V9")
			(options
				(clearance outline)
				(anchor circle)
			)
			(primitives
				(gr_poly
					(pts
						(arc
							(start 0.1524 0.127)
							(mid 0.137521 0.162921)
							(end 0.1016 0.1778)
						)
						(arc
							(start -0.1016 0.1778)
							(mid -0.137521 0.162921)
							(end -0.1524 0.127)
						)
						(arc
							(start -0.1524 -0.127)
							(mid -0.137521 -0.162921)
							(end -0.1016 -0.1778)
						)
						(arc
							(start 0.1016 -0.1778)
							(mid 0.137521 -0.162921)
							(end 0.1524 -0.127)
						)
					)
					(width 0)
					(fill yes)
				)
			)
		)
		(pad "2" smd custom
			(at 0 0.2794 180)
			(size 0.0762 0.0762)
			(layers "B.Cu" "B.Mask" "B.Paste")
			(net "GND")
			(options
				(clearance outline)
				(anchor circle)
			)
			(primitives
				(gr_poly
					(pts
						(arc
							(start 0.1524 0.127)
							(mid 0.137521 0.162921)
							(end 0.1016 0.1778)
						)
						(arc
							(start -0.1016 0.1778)
							(mid -0.137521 0.162921)
							(end -0.1524 0.127)
						)
						(arc
							(start -0.1524 -0.127)
							(mid -0.137521 -0.162921)
							(end -0.1016 -0.1778)
						)
						(arc
							(start 0.1016 -0.1778)
							(mid 0.137521 -0.162921)
							(end 0.1524 -0.127)
						)
					)
					(width 0)
					(fill yes)
				)
			)
		)
	)
	(footprint ""
		(layer "B.Cu")
		(at 120.0404 -78.8416)
		(property "Reference" "TP27"
			(at 0 0 0)
			(layer "B.SilkS")
			(hide yes)
			(effects
				(font
					(size 1.27 1.27)
				)
				(justify mirror)
			)
		)
		(property "Value" "TPAD28-2-GP"
			(at 0.0127 -1.6637 0)
			(unlocked yes)
			(layer "B.Fab")
			(hide yes)
			(effects
				(font
					(size 1.016 1.016)
					(thickness 0.1524)
				)
				(justify mirror)
			)
		)
		(property "Device Type" "TPAD28"
			(at 0.0127 -3.1877 0)
			(unlocked yes)
			(layer "B.Fab")
			(hide yes)
			(effects
				(font
					(size 1.016 1.016)
					(thickness 0.1524)
				)
				(justify mirror)
			)
		)
		(duplicate_pad_numbers_are_jumpers no)
		(fp_poly
			(pts
				(arc
					(start 0.3556 0)
					(mid -0.3556 0)
					(end 0.3556 0)
				)
			)
			(stroke
				(width 0)
				(type default)
			)
			(fill no)
			(layer "B.CrtYd")
		)
		(fp_poly
			(pts
				(arc
					(start 0.6096 0)
					(mid -0.6096 0)
					(end 0.6096 0)
				)
			)
			(stroke
				(width 0)
				(type default)
			)
			(fill no)
			(layer "B.Fab")
		)
		(pad "1" smd circle
			(at 0 0 180)
			(size 0.7112 0.7112)
			(layers "B.Cu" "B.Mask" "B.Paste")
			(net "EXP_GPIO12")
		)
	)
	(footprint ""
		(layer "B.Cu")
		(at 139.5476 -123.87326 180)
		(property "Reference" "R2"
			(at 0 0 0)
			(layer "B.SilkS")
			(hide yes)
			(effects
				(font
					(size 1.27 1.27)
				)
				(justify mirror)
			)
		)
		(property "Value" "10KR2F-2-GP"
			(at -0.064008 -3.993896 180)
			(unlocked yes)
			(layer "B.Fab")
			(hide yes)
			(effects
				(font
					(size 1.016 1.016)
					(thickness 0.1524)
				)
				(justify mirror)
			)
		)
		(property "Device Type" "R402H16"
			(at -0.064008 -5.517896 180)
			(unlocked yes)
			(layer "B.Fab")
			(hide yes)
			(effects
				(font
					(size 1.016 1.016)
					(thickness 0.1524)
				)
				(justify mirror)
			)
		)
		(duplicate_pad_numbers_are_jumpers no)
		(fp_line
			(start 0.508 -0.9398)
			(end 0.508 0.9398)
			(stroke
				(width 0.1524)
				(type default)
			)
			(layer "B.SilkS")
		)
		(fp_line
			(start -0.508 -0.9398)
			(end 0.508 -0.9398)
			(stroke
				(width 0.1524)
				(type default)
			)
			(layer "B.SilkS")
		)
		(fp_rect
			(start 0.508 0.9398)
			(end -0.508 -0.9398)
			(stroke
				(width 0)
				(type default)
			)
			(fill no)
			(layer "B.CrtYd")
		)
		(fp_rect
			(start 0.508 0.9398)
			(end -0.508 -0.9398)
			(stroke
				(width 0)
				(type default)
			)
			(fill no)
			(layer "B.Fab")
		)
		(pad "1" smd custom
			(at 0 -0.4445)
			(size 0.1397 0.1397)
			(layers "B.Cu" "B.Mask" "B.Paste")
			(net "P12V_STBY_SCC")
			(options
				(clearance outline)
				(anchor circle)
			)
			(primitives
				(gr_poly
					(pts
						(arc
							(start -0.1778 0.2794)
							(mid -0.249642 0.249642)
							(end -0.2794 0.1778)
						)
						(arc
							(start -0.2794 -0.1778)
							(mid -0.249642 -0.249642)
							(end -0.1778 -0.2794)
						)
						(arc
							(start 0.1778 -0.2794)
							(mid 0.249642 -0.249642)
							(end 0.2794 -0.1778)
						)
						(arc
							(start 0.2794 0.1778)
							(mid 0.249642 0.249642)
							(end 0.1778 0.2794)
						)
					)
					(width 0)
					(fill yes)
				)
			)
		)
		(pad "2" smd custom
			(at 0 0.4445)
			(size 0.1397 0.1397)
			(layers "B.Cu" "B.Mask" "B.Paste")
			(net "P12V_STBY_Q10_G")
			(options
				(clearance outline)
				(anchor circle)
			)
			(primitives
				(gr_poly
					(pts
						(arc
							(start -0.1778 0.2794)
							(mid -0.249642 0.249642)
							(end -0.2794 0.1778)
						)
						(arc
							(start -0.2794 -0.1778)
							(mid -0.249642 -0.249642)
							(end -0.1778 -0.2794)
						)
						(arc
							(start 0.1778 -0.2794)
							(mid 0.249642 -0.249642)
							(end 0.2794 -0.1778)
						)
						(arc
							(start 0.2794 0.1778)
							(mid 0.249642 0.249642)
							(end 0.1778 0.2794)
						)
					)
					(width 0)
					(fill yes)
				)
			)
		)
	)
)
